(kicad_pcb
	(version 20260206)
	(generator "pcbnew")
	(generator_version "10.0")
	(general
		(thickness 1.6)
		(legacy_teardrops no)
	)
	(paper "A4")
	(title_block
		(title "Wiwynn_Tioga_Pass_MB.brd")
		(comment 1 "Tioga Pass / footprints 328-334 of 4770")
	)
	(layers
		(0 "F.Cu" signal "TOP")
		(4 "In1.Cu" signal "L2GND")
		(6 "In2.Cu" signal "L3")
		(8 "In3.Cu" signal "L4GND")
		(10 "In4.Cu" signal "L5")
		(12 "In5.Cu" signal "L6GND")
		(14 "In6.Cu" signal "L7VCC")
		(16 "In7.Cu" signal "L8VCC")
		(18 "In8.Cu" signal "L9GND")
		(20 "In9.Cu" signal "L10")
		(22 "In10.Cu" signal "L11GND")
		(24 "In11.Cu" signal "L12")
		(26 "In12.Cu" signal "L13GND")
		(2 "B.Cu" signal "BOTTOM")
		(9 "F.Adhes" user "F.Adhesive")
		(11 "B.Adhes" user "B.Adhesive")
		(13 "F.Paste" user "Package Geometry/Pastemask Top")
		(15 "B.Paste" user "Package Geometry/Pastemask Bottom")
		(5 "F.SilkS" user "Ref Des/Silkscreen Top")
		(7 "B.SilkS" user "Ref Des/Silkscreen Bottom")
		(1 "F.Mask" user "Board Geometry/Soldermask Top")
		(3 "B.Mask" user "Board Geometry/Soldermask Bottom")
		(17 "Dwgs.User" user "User.Drawings")
		(19 "Cmts.User" user "User.Comments")
		(21 "Eco1.User" user "User.Eco1")
		(23 "Eco2.User" user "User.Eco2")
		(25 "Edge.Cuts" user "Board Geometry/Outline")
		(27 "Margin" user)
		(31 "F.CrtYd" user "Package Geometry/Place Bound Top")
		(29 "B.CrtYd" user "Package Geometry/Place Bound Bottom")
		(35 "F.Fab" user "Ref Des/Assembly Top")
		(33 "B.Fab" user "Ref Des/Assembly Bottom")
	)
	(footprint ""
		(layer "F.Cu")
		(at 385.8768 -51.6128 180)
		(property "Reference" "R7F29"
			(at 0 0 180)
			(layer "F.SilkS")
			(hide yes)
			(effects
				(font
					(size 1.27 1.27)
				)
			)
		)
		(property "Value" ""
			(at 0 0 180)
			(layer "F.Fab")
			(effects
				(font
					(size 1.27 1.27)
				)
			)
		)
		(duplicate_pad_numbers_are_jumpers no)
		(fp_poly
			(pts
				(xy -0.2794 -0.1016) (xy 0.2794 -0.1016) (xy 0.2794 0.9906) (xy -0.2794 0.9906)
			)
			(stroke
				(width 0)
				(type default)
			)
			(fill no)
			(layer "F.CrtYd")
		)
		(fp_line
			(start 0.2794 0.9906)
			(end 0.2794 -0.1016)
			(stroke
				(width 0.1)
				(type default)
			)
			(layer "F.Fab")
		)
		(fp_line
			(start 0.2794 -0.1016)
			(end -0.2794 -0.1016)
			(stroke
				(width 0.1)
				(type default)
			)
			(layer "F.Fab")
		)
		(fp_line
			(start -0.2794 0.9906)
			(end 0.2794 0.9906)
			(stroke
				(width 0.1)
				(type default)
			)
			(layer "F.Fab")
		)
		(fp_line
			(start -0.2794 -0.1016)
			(end -0.2794 0.9906)
			(stroke
				(width 0.1)
				(type default)
			)
			(layer "F.Fab")
		)
		(pad "1" smd rect
			(at 0 0 180)
			(size 0.508 0.508)
			(layers "F.Cu" "F.Mask" "F.Paste")
			(net "SPI_SWITCH_MOSI")
		)
		(pad "2" smd rect
			(at 0 0.889 180)
			(size 0.508 0.508)
			(layers "F.Cu" "F.Mask" "F.Paste")
			(net "SPI_SWITCH_MOSI_R0")
		)
		(zone
			(layer "F.Cu")
			(hatch none 0.5)
			(connect_pads
				(clearance 0)
			)
			(min_thickness 0.25)
			(keepout
				(tracks not_allowed)
				(vias allowed)
				(pads allowed)
				(copperpour not_allowed)
				(footprints allowed)
			)
			(placement
				(enabled no)
				(sheetname "")
			)
			(fill
				(thermal_gap 0.5)
				(thermal_bridge_width 0.5)
				(island_removal_mode 0)
			)
			(polygon
				(pts
					(xy 386.1308 -52.2478) (xy 385.6228 -52.2478) (xy 385.6228 -51.8668) (xy 386.1308 -51.8668)
				)
			)
		)
		(zone
			(layer "F.Cu")
			(hatch none 0.5)
			(connect_pads
				(clearance 0)
			)
			(min_thickness 0.25)
			(keepout
				(tracks allowed)
				(vias not_allowed)
				(pads allowed)
				(copperpour not_allowed)
				(footprints allowed)
			)
			(placement
				(enabled no)
				(sheetname "")
			)
			(fill
				(thermal_gap 0.5)
				(thermal_bridge_width 0.5)
				(island_removal_mode 0)
			)
			(polygon
				(pts
					(xy 386.1308 -51.8668) (xy 385.6228 -51.8668) (xy 385.6228 -52.2478) (xy 386.1308 -52.2478)
				)
			)
		)
	)
	(footprint ""
		(layer "F.Cu")
		(at 370.366544 -10.916158)
		(property "Reference" "C7G12"
			(at 0 0 0)
			(layer "F.SilkS")
			(hide yes)
			(effects
				(font
					(size 1.27 1.27)
				)
			)
		)
		(property "Value" ""
			(at 0 0 0)
			(layer "F.Fab")
			(effects
				(font
					(size 1.27 1.27)
				)
			)
		)
		(duplicate_pad_numbers_are_jumpers no)
		(fp_rect
			(start -0.3048 0.9906)
			(end 0.3048 -0.1016)
			(stroke
				(width 0)
				(type default)
			)
			(fill no)
			(layer "F.CrtYd")
		)
		(fp_line
			(start -0.3048 -0.1016)
			(end -0.3048 0.9906)
			(stroke
				(width 0.1)
				(type default)
			)
			(layer "F.Fab")
		)
		(fp_line
			(start -0.3048 0.9906)
			(end 0.3048 0.9906)
			(stroke
				(width 0.1)
				(type default)
			)
			(layer "F.Fab")
		)
		(fp_line
			(start 0.3048 -0.1016)
			(end -0.3048 -0.1016)
			(stroke
				(width 0.1)
				(type default)
			)
			(layer "F.Fab")
		)
		(fp_line
			(start 0.3048 0.9906)
			(end 0.3048 -0.1016)
			(stroke
				(width 0.1)
				(type default)
			)
			(layer "F.Fab")
		)
		(pad "1" smd rect
			(at 0 0)
			(size 0.508 0.508)
			(layers "F.Cu" "F.Mask" "F.Paste")
			(net "P3E_CPU0_PE2_SS_TXN<12>")
		)
		(pad "2" smd rect
			(at 0 0.889)
			(size 0.508 0.508)
			(layers "F.Cu" "F.Mask" "F.Paste")
			(net "P3E_CPU0_PE2_SS_C_TXN<12>")
		)
		(zone
			(layer "F.Cu")
			(hatch none 0.5)
			(connect_pads
				(clearance 0)
			)
			(min_thickness 0.25)
			(keepout
				(tracks not_allowed)
				(vias allowed)
				(pads allowed)
				(copperpour not_allowed)
				(footprints allowed)
			)
			(placement
				(enabled no)
				(sheetname "")
			)
			(fill
				(thermal_gap 0.5)
				(thermal_bridge_width 0.5)
				(island_removal_mode 0)
			)
			(polygon
				(pts
					(xy 370.112544 -10.281158) (xy 370.620544 -10.281158) (xy 370.620544 -10.662158) (xy 370.112544 -10.662158)
				)
			)
		)
		(zone
			(layer "F.Cu")
			(hatch none 0.5)
			(connect_pads
				(clearance 0)
			)
			(min_thickness 0.25)
			(keepout
				(tracks allowed)
				(vias not_allowed)
				(pads allowed)
				(copperpour not_allowed)
				(footprints allowed)
			)
			(placement
				(enabled no)
				(sheetname "")
			)
			(fill
				(thermal_gap 0.5)
				(thermal_bridge_width 0.5)
				(island_removal_mode 0)
			)
			(polygon
				(pts
					(xy 370.112544 -10.281158) (xy 370.620544 -10.281158) (xy 370.620544 -10.662158) (xy 370.112544 -10.662158)
				)
			)
		)
	)
	(footprint ""
		(layer "F.Cu")
		(at 405.283416 -147.420584 90)
		(property "Reference" "R8A11"
			(at 0 0 90)
			(layer "F.SilkS")
			(hide yes)
			(effects
				(font
					(size 1.27 1.27)
				)
			)
		)
		(property "Value" ""
			(at 0 0 90)
			(layer "F.Fab")
			(effects
				(font
					(size 1.27 1.27)
				)
			)
		)
		(duplicate_pad_numbers_are_jumpers no)
		(fp_poly
			(pts
				(xy -0.2794 -0.1016) (xy 0.2794 -0.1016) (xy 0.2794 0.9906) (xy -0.2794 0.9906)
			)
			(stroke
				(width 0)
				(type default)
			)
			(fill no)
			(layer "F.CrtYd")
		)
		(fp_line
			(start 0.2794 -0.1016)
			(end -0.2794 -0.1016)
			(stroke
				(width 0.1)
				(type default)
			)
			(layer "F.Fab")
		)
		(fp_line
			(start -0.2794 -0.1016)
			(end -0.2794 0.9906)
			(stroke
				(width 0.1)
				(type default)
			)
			(layer "F.Fab")
		)
		(fp_line
			(start 0.2794 0.9906)
			(end 0.2794 -0.1016)
			(stroke
				(width 0.1)
				(type default)
			)
			(layer "F.Fab")
		)
		(fp_line
			(start -0.2794 0.9906)
			(end 0.2794 0.9906)
			(stroke
				(width 0.1)
				(type default)
			)
			(layer "F.Fab")
		)
		(pad "1" smd rect
			(at 0 0 90)
			(size 0.508 0.508)
			(layers "F.Cu" "F.Mask" "F.Paste")
			(net "PWRGD_P1V8_PCH_STBY_R")
		)
		(pad "2" smd rect
			(at 0 0.889 90)
			(size 0.508 0.508)
			(layers "F.Cu" "F.Mask" "F.Paste")
			(net "PWRGD_P1V8_PCH_STBY")
		)
		(zone
			(layer "F.Cu")
			(hatch none 0.5)
			(connect_pads
				(clearance 0)
			)
			(min_thickness 0.25)
			(keepout
				(tracks allowed)
				(vias not_allowed)
				(pads allowed)
				(copperpour not_allowed)
				(footprints allowed)
			)
			(placement
				(enabled no)
				(sheetname "")
			)
			(fill
				(thermal_gap 0.5)
				(thermal_bridge_width 0.5)
				(island_removal_mode 0)
			)
			(polygon
				(pts
					(xy 405.537416 -147.166584) (xy 405.537416 -147.674584) (xy 405.918416 -147.674584) (xy 405.918416 -147.166584)
				)
			)
		)
		(zone
			(layer "F.Cu")
			(hatch none 0.5)
			(connect_pads
				(clearance 0)
			)
			(min_thickness 0.25)
			(keepout
				(tracks not_allowed)
				(vias allowed)
				(pads allowed)
				(copperpour not_allowed)
				(footprints allowed)
			)
			(placement
				(enabled no)
				(sheetname "")
			)
			(fill
				(thermal_gap 0.5)
				(thermal_bridge_width 0.5)
				(island_removal_mode 0)
			)
			(polygon
				(pts
					(xy 405.918416 -147.166584) (xy 405.918416 -147.674584) (xy 405.537416 -147.674584) (xy 405.537416 -147.166584)
				)
			)
		)
	)
	(footprint ""
		(layer "F.Cu")
		(at 393.916408 -61.773308 180)
		(property "Reference" "R8E37"
			(at 0 0 180)
			(layer "F.SilkS")
			(hide yes)
			(effects
				(font
					(size 1.27 1.27)
				)
			)
		)
		(property "Value" ""
			(at 0 0 180)
			(layer "F.Fab")
			(effects
				(font
					(size 1.27 1.27)
				)
			)
		)
		(duplicate_pad_numbers_are_jumpers no)
		(fp_poly
			(pts
				(xy -0.2794 -0.1016) (xy 0.2794 -0.1016) (xy 0.2794 0.9906) (xy -0.2794 0.9906)
			)
			(stroke
				(width 0)
				(type default)
			)
			(fill no)
			(layer "F.CrtYd")
		)
		(fp_line
			(start 0.2794 0.9906)
			(end 0.2794 -0.1016)
			(stroke
				(width 0.1)
				(type default)
			)
			(layer "F.Fab")
		)
		(fp_line
			(start 0.2794 -0.1016)
			(end -0.2794 -0.1016)
			(stroke
				(width 0.1)
				(type default)
			)
			(layer "F.Fab")
		)
		(fp_line
			(start -0.2794 0.9906)
			(end 0.2794 0.9906)
			(stroke
				(width 0.1)
				(type default)
			)
			(layer "F.Fab")
		)
		(fp_line
			(start -0.2794 -0.1016)
			(end -0.2794 0.9906)
			(stroke
				(width 0.1)
				(type default)
			)
			(layer "F.Fab")
		)
		(pad "1" smd rect
			(at 0 0 180)
			(size 0.508 0.508)
			(layers "F.Cu" "F.Mask" "F.Paste")
			(net "VR_P5V_STBY_VSENSE_R")
		)
		(pad "2" smd rect
			(at 0 0.889 180)
			(size 0.508 0.508)
			(layers "F.Cu" "F.Mask" "F.Paste")
			(net "P5V_STBY")
		)
		(zone
			(layer "F.Cu")
			(hatch none 0.5)
			(connect_pads
				(clearance 0)
			)
			(min_thickness 0.25)
			(keepout
				(tracks not_allowed)
				(vias allowed)
				(pads allowed)
				(copperpour not_allowed)
				(footprints allowed)
			)
			(placement
				(enabled no)
				(sheetname "")
			)
			(fill
				(thermal_gap 0.5)
				(thermal_bridge_width 0.5)
				(island_removal_mode 0)
			)
			(polygon
				(pts
					(xy 394.170408 -62.408308) (xy 393.662408 -62.408308) (xy 393.662408 -62.027308) (xy 394.170408 -62.027308)
				)
			)
		)
		(zone
			(layer "F.Cu")
			(hatch none 0.5)
			(connect_pads
				(clearance 0)
			)
			(min_thickness 0.25)
			(keepout
				(tracks allowed)
				(vias not_allowed)
				(pads allowed)
				(copperpour not_allowed)
				(footprints allowed)
			)
			(placement
				(enabled no)
				(sheetname "")
			)
			(fill
				(thermal_gap 0.5)
				(thermal_bridge_width 0.5)
				(island_removal_mode 0)
			)
			(polygon
				(pts
					(xy 394.170408 -62.027308) (xy 393.662408 -62.027308) (xy 393.662408 -62.408308) (xy 394.170408 -62.408308)
				)
			)
		)
	)
	(footprint ""
		(layer "F.Cu")
		(at 456.5015 -24.8412 -90)
		(property "Reference" "C1W7"
			(at 0.97536 0.76708 180)
			(unlocked yes)
			(layer "F.SilkS")
			(effects
				(font
					(size 0.4064 0.254)
					(thickness 0.1524)
				)
			)
		)
		(property "Value" ""
			(at 0 0 270)
			(layer "F.Fab")
			(effects
				(font
					(size 1.27 1.27)
				)
			)
		)
		(duplicate_pad_numbers_are_jumpers no)
		(fp_poly
			(pts
				(xy -0.4953 -0.2032) (xy 0.4953 -0.2032) (xy 0.4953 1.6002) (xy -0.4953 1.6002)
			)
			(stroke
				(width 0)
				(type default)
			)
			(fill no)
			(layer "F.CrtYd")
		)
		(fp_line
			(start -0.4953 1.6002)
			(end -0.4953 -0.2032)
			(stroke
				(width 0.1)
				(type default)
			)
			(layer "F.Fab")
		)
		(fp_line
			(start 0.4953 1.6002)
			(end -0.4953 1.6002)
			(stroke
				(width 0.1)
				(type default)
			)
			(layer "F.Fab")
		)
		(fp_line
			(start -0.4953 -0.2032)
			(end 0.4953 -0.2032)
			(stroke
				(width 0.1)
				(type default)
			)
			(layer "F.Fab")
		)
		(fp_line
			(start 0.4953 -0.2032)
			(end 0.4953 1.6002)
			(stroke
				(width 0.1)
				(type default)
			)
			(layer "F.Fab")
		)
		(pad "1" smd rect
			(at 0 0 270)
			(size 0.762 0.889)
			(layers "F.Cu" "F.Mask" "F.Paste")
			(net "P3V3_STBY")
		)
		(pad "2" smd rect
			(at 0 1.397 270)
			(size 0.762 0.889)
			(layers "F.Cu" "F.Mask" "F.Paste")
			(net "GND")
		)
		(zone
			(layer "F.Cu")
			(hatch none 0.5)
			(connect_pads
				(clearance 0)
			)
			(min_thickness 0.25)
			(keepout
				(tracks not_allowed)
				(vias allowed)
				(pads allowed)
				(copperpour not_allowed)
				(footprints allowed)
			)
			(placement
				(enabled no)
				(sheetname "")
			)
			(fill
				(thermal_gap 0.5)
				(thermal_bridge_width 0.5)
				(island_removal_mode 0)
			)
			(polygon
				(pts
					(xy 456.057 -25.2222) (xy 456.057 -24.4602) (xy 455.549 -24.4602) (xy 455.549 -25.2222)
				)
			)
		)
	)
	(footprint ""
		(layer "F.Cu")
		(at 390.652 -87.3125 180)
		(property "Reference" "R2P1"
			(at 0 0 180)
			(layer "F.SilkS")
			(hide yes)
			(effects
				(font
					(size 1.27 1.27)
				)
			)
		)
		(property "Value" ""
			(at 0 0 180)
			(layer "F.Fab")
			(effects
				(font
					(size 1.27 1.27)
				)
			)
		)
		(duplicate_pad_numbers_are_jumpers no)
		(fp_poly
			(pts
				(xy -0.2794 -0.1016) (xy 0.2794 -0.1016) (xy 0.2794 0.9906) (xy -0.2794 0.9906)
			)
			(stroke
				(width 0)
				(type default)
			)
			(fill no)
			(layer "F.CrtYd")
		)
		(fp_line
			(start 0.2794 0.9906)
			(end 0.2794 -0.1016)
			(stroke
				(width 0.1)
				(type default)
			)
			(layer "F.Fab")
		)
		(fp_line
			(start 0.2794 -0.1016)
			(end -0.2794 -0.1016)
			(stroke
				(width 0.1)
				(type default)
			)
			(layer "F.Fab")
		)
		(fp_line
			(start -0.2794 0.9906)
			(end 0.2794 0.9906)
			(stroke
				(width 0.1)
				(type default)
			)
			(layer "F.Fab")
		)
		(fp_line
			(start -0.2794 -0.1016)
			(end -0.2794 0.9906)
			(stroke
				(width 0.1)
				(type default)
			)
			(layer "F.Fab")
		)
		(pad "1" smd rect
			(at 0 0 180)
			(size 0.508 0.508)
			(layers "F.Cu" "F.Mask" "F.Paste")
			(net "RMII_SPRNGVLLE_BMC_PCH_RXD1")
		)
		(pad "2" smd rect
			(at 0 0.889 180)
			(size 0.508 0.508)
			(layers "F.Cu" "F.Mask" "F.Paste")
			(net "RMII_SPRNGVLLE_BMC_PCH_RXD1_R1")
		)
		(zone
			(layer "F.Cu")
			(hatch none 0.5)
			(connect_pads
				(clearance 0)
			)
			(min_thickness 0.25)
			(keepout
				(tracks not_allowed)
				(vias allowed)
				(pads allowed)
				(copperpour not_allowed)
				(footprints allowed)
			)
			(placement
				(enabled no)
				(sheetname "")
			)
			(fill
				(thermal_gap 0.5)
				(thermal_bridge_width 0.5)
				(island_removal_mode 0)
			)
			(polygon
				(pts
					(xy 390.906 -87.9475) (xy 390.398 -87.9475) (xy 390.398 -87.5665) (xy 390.906 -87.5665)
				)
			)
		)
		(zone
			(layer "F.Cu")
			(hatch none 0.5)
			(connect_pads
				(clearance 0)
			)
			(min_thickness 0.25)
			(keepout
				(tracks allowed)
				(vias not_allowed)
				(pads allowed)
				(copperpour not_allowed)
				(footprints allowed)
			)
			(placement
				(enabled no)
				(sheetname "")
			)
			(fill
				(thermal_gap 0.5)
				(thermal_bridge_width 0.5)
				(island_removal_mode 0)
			)
			(polygon
				(pts
					(xy 390.906 -87.5665) (xy 390.398 -87.5665) (xy 390.398 -87.9475) (xy 390.906 -87.9475)
				)
			)
		)
	)
	(footprint ""
		(layer "F.Cu")
		(at 328.9808 -26.6827 180)
		(property "Reference" "C6F4"
			(at 2.91973 -1.9812 90)
			(unlocked yes)
			(layer "F.SilkS")
			(effects
				(font
					(size 0.7874 0.5842)
					(thickness 0.1524)
				)
				(justify left)
			)
		)
		(property "Value" ""
			(at 0 0 180)
			(layer "F.Fab")
			(effects
				(font
					(size 1.27 1.27)
				)
			)
		)
		(duplicate_pad_numbers_are_jumpers no)
		(fp_line
			(start 2.2987 7.3533)
			(end 2.2987 -0.2413)
			(stroke
				(width 0.1524)
				(type default)
			)
			(layer "F.SilkS")
		)
		(fp_line
			(start 2.2987 -0.2413)
			(end 2.032 -0.2413)
			(stroke
				(width 0.1524)
				(type default)
			)
			(layer "F.SilkS")
		)
		(fp_line
			(start 2.032 1.524)
			(end 1.7272 1.524)
			(stroke
				(width 0.1524)
				(type default)
			)
			(layer "F.SilkS")
		)
		(fp_line
			(start 2.032 -1.524)
			(end 2.032 1.524)
			(stroke
				(width 0.1524)
				(type default)
			)
			(layer "F.SilkS")
		)
		(fp_line
			(start 1.7272 7.3533)
			(end 2.2987 7.3533)
			(stroke
				(width 0.1524)
				(type default)
			)
			(layer "F.SilkS")
		)
		(fp_line
			(start 1.7272 -1.524)
			(end 2.032 -1.524)
			(stroke
				(width 0.1524)
				(type default)
			)
			(layer "F.SilkS")
		)
		(fp_line
			(start -1.7272 -1.524)
			(end -2.032 -1.524)
			(stroke
				(width 0.1524)
				(type default)
			)
			(layer "F.SilkS")
		)
		(fp_line
			(start -2.032 1.524)
			(end -1.7272 1.524)
			(stroke
				(width 0.1524)
				(type default)
			)
			(layer "F.SilkS")
		)
		(fp_line
			(start -2.032 -0.2413)
			(end -2.2987 -0.2413)
			(stroke
				(width 0.1524)
				(type default)
			)
			(layer "F.SilkS")
		)
		(fp_line
			(start -2.032 -1.524)
			(end -2.032 1.524)
			(stroke
				(width 0.1524)
				(type default)
			)
			(layer "F.SilkS")
		)
		(fp_line
			(start -2.2987 7.3533)
			(end -1.7272 7.3533)
			(stroke
				(width 0.1524)
				(type default)
			)
			(layer "F.SilkS")
		)
		(fp_line
			(start -2.2987 -0.2413)
			(end -2.2987 7.3533)
			(stroke
				(width 0.1524)
				(type default)
			)
			(layer "F.SilkS")
		)
		(fp_rect
			(start 2.2987 -0.2413)
			(end -2.2987 7.3533)
			(stroke
				(width 0)
				(type default)
			)
			(fill no)
			(layer "F.CrtYd")
		)
		(fp_line
			(start 2.2987 7.3533)
			(end -2.2987 7.3533)
			(stroke
				(width 0.1)
				(type default)
			)
			(layer "F.Fab")
		)
		(fp_line
			(start 2.2987 -0.2413)
			(end 2.2987 7.3533)
			(stroke
				(width 0.1)
				(type default)
			)
			(layer "F.Fab")
		)
		(fp_line
			(start -2.2987 7.3533)
			(end -2.2987 -0.2413)
			(stroke
				(width 0.1)
				(type default)
			)
			(layer "F.Fab")
		)
		(fp_line
			(start -2.2987 -0.2413)
			(end 2.2987 -0.2413)
			(stroke
				(width 0.1)
				(type default)
			)
			(layer "F.Fab")
		)
		(pad "1" smd rect
			(at 0 0 180)
			(size 2.54 3.048)
			(layers "F.Cu" "F.Mask" "F.Paste")
			(net "PVPP_ABC")
		)
		(pad "2" smd rect
			(at 0 7.112 180)
			(size 2.54 3.048)
			(layers "F.Cu" "F.Mask" "F.Paste")
			(net "GND")
		)
	)
)
